# S9S_MB_2U (Grand Teton) — schematic netlist excerpt (pin names and nets, part order shuffled) for the footprints in the layout excerpt that follows; sources: Cadence DE-HDL packaged netlist, KiCad conversion of 03242023_DA0F0TMBIJ0_F0T_Motherboard_J_brd_V01_OCP.brd

DB12  TDR_3P  EMPTY  pkg TH2  page 309
  GND  = T1_GND
  IO1  = TDR_SE_50_OHM_BOT
  IO2  = TDR_SE_50_OHM_BOT

(kicad_pcb
	(version 20260206)
	(generator "pcbnew")
	(generator_version "10.0")
	(general
		(thickness 1.6)
		(legacy_teardrops no)
	)
	(paper "A4")
	(title_block
		(title "03242023_DA0F0TMBIJ0_F0T_Motherboard_J_brd_V01_OCP.brd")
		(comment 1 "Grand Teton / footprints 4211-4211 of 6105")
	)
	(layers
		(0 "F.Cu" signal "TOP")
		(4 "In1.Cu" signal "GND")
		(6 "In2.Cu" signal "IN1")
		(8 "In3.Cu" signal "GND1")
		(10 "In4.Cu" signal "IN2")
		(12 "In5.Cu" signal "GND2")
		(14 "In6.Cu" signal "IN3")
		(16 "In7.Cu" signal "GND3")
		(18 "In8.Cu" signal "VCC")
		(20 "In9.Cu" signal "VCC1")
		(22 "In10.Cu" signal "GND4")
		(24 "In11.Cu" signal "IN4")
		(26 "In12.Cu" signal "GND5")
		(28 "In13.Cu" signal "IN5")
		(30 "In14.Cu" signal "GND6")
		(32 "In15.Cu" signal "IN6")
		(34 "In16.Cu" signal "GND7")
		(2 "B.Cu" signal "BOTTOM")
		(9 "F.Adhes" user "F.Adhesive")
		(11 "B.Adhes" user "B.Adhesive")
		(13 "F.Paste" user "Package Geometry/Pastemask Top")
		(15 "B.Paste" user "Package Geometry/Pastemask Bottom")
		(5 "F.SilkS" user "Ref Des/Silkscreen Top")
		(7 "B.SilkS" user "Ref Des/Silkscreen Bottom")
		(1 "F.Mask" user "Board Geometry/Soldermask Top")
		(3 "B.Mask" user "Board Geometry/Soldermask Bottom")
		(17 "Dwgs.User" user "User.Drawings")
		(19 "Cmts.User" user "User.Comments")
		(21 "Eco1.User" user "User.Eco1")
		(23 "Eco2.User" user "User.Eco2")
		(25 "Edge.Cuts" user "Board Geometry/Outline")
		(27 "Margin" user)
		(31 "F.CrtYd" user "Package Geometry/Place Bound Top")
		(29 "B.CrtYd" user "Package Geometry/Place Bound Bottom")
		(35 "F.Fab" user "Ref Des/Assembly Top")
		(33 "B.Fab" user "Ref Des/Assembly Bottom")
	)
	(footprint ""
		(layer "B.Cu")
		(at 477.95688 -251.022866)
		(property "Reference" "DB12"
			(at 2.467356 -5.911342 270)
			(unlocked yes)
			(layer "B.SilkS")
			(effects
				(font
					(size 0.7874 0.5842)
					(thickness 0.1524)
				)
				(justify left mirror)
			)
		)
		(property "Value" ""
			(at 0 0 0)
			(layer "B.Fab")
			(effects
				(font
					(size 1.27 1.27)
				)
				(justify mirror)
			)
		)
		(duplicate_pad_numbers_are_jumpers no)
		(fp_line
			(start -3.330702 -4.771136)
			(end 0 4.011168)
			(stroke
				(width 0.1524)
				(type default)
			)
			(layer "B.SilkS")
		)
		(fp_line
			(start 0 4.011168)
			(end 3.330702 -4.771136)
			(stroke
				(width 0.1524)
				(type default)
			)
			(layer "B.SilkS")
		)
		(fp_line
			(start 3.330702 -4.771136)
			(end -3.330702 -4.771136)
			(stroke
				(width 0.1524)
				(type default)
			)
			(layer "B.SilkS")
		)
		(fp_line
			(start -3.330702 -4.771136)
			(end 0 4.011168)
			(stroke
				(width 0.1)
				(type default)
			)
			(layer "B.Fab")
		)
		(fp_line
			(start 0 4.011168)
			(end 3.330702 -4.771136)
			(stroke
				(width 0.1)
				(type default)
			)
			(layer "B.Fab")
		)
		(fp_line
			(start 3.330702 -4.771136)
			(end -3.330702 -4.771136)
			(stroke
				(width 0.1)
				(type default)
			)
			(layer "B.Fab")
		)
		(pad "1" thru_hole circle
			(at 0 0 180)
			(size 2.159 2.159)
			(drill 1.7018)
			(layers "*.Cu" "*.Mask")
			(remove_unused_layers no)
			(net "T1_GND")
			(clearance 0.0254)
			(thermal_gap 0.0254)
		)
		(pad "2" thru_hole circle
			(at 1.27 -3.348736 180)
			(size 2.159 2.159)
			(drill 1.7018)
			(layers "*.Cu" "*.Mask")
			(remove_unused_layers no)
			(net "TDR_SE_50_OHM_BOT")
			(clearance 0.0254)
			(thermal_gap 0.0254)
		)
		(pad "3" thru_hole circle
			(at -1.27 -3.348736 180)
			(size 2.159 2.159)
			(drill 1.7018)
			(layers "*.Cu" "*.Mask")
			(remove_unused_layers no)
			(net "TDR_SE_50_OHM_BOT")
			(clearance 0.0254)
			(thermal_gap 0.0254)
		)
	)
)
